(kicad_pcb
	(version 20260206)
	(generator "pcbnew")
	(generator_version "10.0")
	(general
		(thickness 1.6)
		(legacy_teardrops no)
	)
	(paper "A4")
	(title_block
		(title "04192023_DAF0TMB3IC0_F0TG_MB_C_brd_V02_OCP.brd")
		(comment 1 "Grand Teton / footprint 3955 of 8354 (U25), pads 110-218 of 6102")
	)
	(layers
		(0 "F.Cu" signal "TOP")
		(4 "In1.Cu" signal "GND")
		(6 "In2.Cu" signal "IN1")
		(8 "In3.Cu" signal "GND1")
		(10 "In4.Cu" signal "IN2")
		(12 "In5.Cu" signal "GND2")
		(14 "In6.Cu" signal "IN3")
		(16 "In7.Cu" signal "GND3")
		(18 "In8.Cu" signal "VCC")
		(20 "In9.Cu" signal "VCC1")
		(22 "In10.Cu" signal "GND4")
		(24 "In11.Cu" signal "IN4")
		(26 "In12.Cu" signal "GND5")
		(28 "In13.Cu" signal "IN5")
		(30 "In14.Cu" signal "GND6")
		(32 "In15.Cu" signal "IN6")
		(34 "In16.Cu" signal "GND7")
		(2 "B.Cu" signal "BOTTOM")
		(9 "F.Adhes" user "F.Adhesive")
		(11 "B.Adhes" user "B.Adhesive")
		(13 "F.Paste" user "Package Geometry/Pastemask Top")
		(15 "B.Paste" user "Package Geometry/Pastemask Bottom")
		(5 "F.SilkS" user "Ref Des/Silkscreen Top")
		(7 "B.SilkS" user "Ref Des/Silkscreen Bottom")
		(1 "F.Mask" user "Board Geometry/Soldermask Top")
		(3 "B.Mask" user "Board Geometry/Soldermask Bottom")
		(17 "Dwgs.User" user "User.Drawings")
		(19 "Cmts.User" user "User.Comments")
		(21 "Eco1.User" user "User.Eco1")
		(23 "Eco2.User" user "User.Eco2")
		(25 "Edge.Cuts" user "Board Geometry/Outline")
		(27 "Margin" user)
		(31 "F.CrtYd" user "Package Geometry/Place Bound Top")
		(29 "B.CrtYd" user "Package Geometry/Place Bound Bottom")
		(35 "F.Fab" user "Ref Des/Assembly Top")
		(33 "B.Fab" user "Ref Des/Assembly Bottom")
	)
	(footprint ""
		(layer "F.Cu")
		(at 359.867962 -258.880102 180)
		(property "Reference" "U25"
			(at -45.78477 -62.086744 0)
			(unlocked yes)
			(layer "F.SilkS")
			(effects
				(font
					(size 0.7874 0.5842)
					(thickness 0.1524)
				)
			)
		)
		(property "Value" ""
			(at 0 0 180)
			(layer "F.Fab")
			(effects
				(font
					(size 1.27 1.27)
				)
			)
		)
		(duplicate_pad_numbers_are_jumpers no)
		(pad "AA51" smd circle
			(at 11.8999 -20.610068 180)
			(size 0.450088 0.450088)
			(layers "F.Cu" "F.Mask" "F.Paste")
			(net "TP_CPU0_TEST5_CCD0")
		)
		(pad "AA52" smd circle
			(at 12.839954 -20.610068 180)
			(size 0.450088 0.450088)
			(layers "F.Cu" "F.Mask" "F.Paste")
			(net "TP_CPU0_TEST4_CCD4")
		)
		(pad "AA53" smd circle
			(at 13.780008 -20.610068 180)
			(size 0.450088 0.450088)
			(layers "F.Cu" "F.Mask" "F.Paste")
			(net "TP_CPU0_TEST5_CCD4")
		)
		(pad "AA54" smd circle
			(at 14.720062 -20.610068 180)
			(size 0.450088 0.450088)
			(layers "F.Cu" "F.Mask" "F.Paste")
			(net "PVDDIO_P0")
		)
		(pad "AA55" smd circle
			(at 15.660116 -20.610068 180)
			(size 0.450088 0.450088)
			(layers "F.Cu" "F.Mask" "F.Paste")
			(net "M_C_CPU0_SA_DQS_DP<7>")
		)
		(pad "AA56" smd circle
			(at 16.599916 -20.610068 180)
			(size 0.450088 0.450088)
			(layers "F.Cu" "F.Mask" "F.Paste")
			(net "GND")
		)
		(pad "AA57" smd circle
			(at 17.53997 -20.610068 180)
			(size 0.450088 0.450088)
			(layers "F.Cu" "F.Mask" "F.Paste")
			(net "M_C_CPU0_SA_DQ<20>")
		)
		(pad "AA58" smd circle
			(at 18.480024 -20.610068 180)
			(size 0.450088 0.450088)
			(layers "F.Cu" "F.Mask" "F.Paste")
			(net "GND")
		)
		(pad "AA59" smd circle
			(at 19.420078 -20.610068 180)
			(size 0.450088 0.450088)
			(layers "F.Cu" "F.Mask" "F.Paste")
			(net "M_D_CPU0_SA_DQS_DP<7>")
		)
		(pad "AA60" smd circle
			(at 20.359878 -20.610068 180)
			(size 0.450088 0.450088)
			(layers "F.Cu" "F.Mask" "F.Paste")
			(net "M_D_CPU0_SA_DQ<20>")
		)
		(pad "AA61" smd circle
			(at 21.299932 -20.610068 180)
			(size 0.450088 0.450088)
			(layers "F.Cu" "F.Mask" "F.Paste")
			(net "GND")
		)
		(pad "AA62" smd circle
			(at 22.239986 -20.610068 180)
			(size 0.450088 0.450088)
			(layers "F.Cu" "F.Mask" "F.Paste")
			(net "M_B_CPU0_SA_DQS_DP<7>")
		)
		(pad "AA63" smd circle
			(at 23.18004 -20.610068 180)
			(size 0.450088 0.450088)
			(layers "F.Cu" "F.Mask" "F.Paste")
			(net "GND")
		)
		(pad "AA64" smd circle
			(at 24.120094 -20.610068 180)
			(size 0.450088 0.450088)
			(layers "F.Cu" "F.Mask" "F.Paste")
			(net "M_B_CPU0_SA_DQ<20>")
		)
		(pad "AA65" smd circle
			(at 25.059894 -20.610068 180)
			(size 0.450088 0.450088)
			(layers "F.Cu" "F.Mask" "F.Paste")
			(net "GND")
		)
		(pad "AA66" smd circle
			(at 25.999948 -20.610068 180)
			(size 0.450088 0.450088)
			(layers "F.Cu" "F.Mask" "F.Paste")
			(net "M_F_CPU0_SA_DQS_DP<7>")
		)
		(pad "AA67" smd circle
			(at 26.940002 -20.610068 180)
			(size 0.450088 0.450088)
			(layers "F.Cu" "F.Mask" "F.Paste")
			(net "M_F_CPU0_SA_DQ<20>")
		)
		(pad "AA68" smd circle
			(at 27.880056 -20.610068 180)
			(size 0.450088 0.450088)
			(layers "F.Cu" "F.Mask" "F.Paste")
			(net "GND")
		)
		(pad "AA69" smd circle
			(at 28.82011 -20.610068 180)
			(size 0.450088 0.450088)
			(layers "F.Cu" "F.Mask" "F.Paste")
			(net "M_E_CPU0_SA_DQS_DP<7>")
		)
		(pad "AA70" smd circle
			(at 29.75991 -20.610068 180)
			(size 0.450088 0.450088)
			(layers "F.Cu" "F.Mask" "F.Paste")
			(net "GND")
		)
		(pad "AA71" smd circle
			(at 30.699964 -20.610068 180)
			(size 0.450088 0.450088)
			(layers "F.Cu" "F.Mask" "F.Paste")
			(net "M_E_CPU0_SA_DQ<20>")
		)
		(pad "AA72" smd circle
			(at 31.640018 -20.610068 180)
			(size 0.450088 0.450088)
			(layers "F.Cu" "F.Mask" "F.Paste")
			(net "GND")
		)
		(pad "AA73" smd circle
			(at 32.580072 -20.610068 180)
			(size 0.450088 0.450088)
			(layers "F.Cu" "F.Mask" "F.Paste")
			(net "M_A_CPU0_SA_DQS_DP<7>")
		)
		(pad "AA74" smd circle
			(at 33.519872 -20.610068 180)
			(size 0.450088 0.450088)
			(layers "F.Cu" "F.Mask" "F.Paste")
			(net "M_A_CPU0_SA_DQ<20>")
		)
		(pad "AA75" smd circle
			(at 34.459926 -20.610068 180)
			(size 0.450088 0.450088)
			(layers "F.Cu" "F.Mask" "F.Paste")
			(net "GND")
		)
		(pad "AB2" smd circle
			(at -33.690052 -19.800062 180)
			(size 0.450088 0.450088)
			(layers "F.Cu" "F.Mask" "F.Paste")
			(net "M_G_CPU0_SA_DQ<22>")
		)
		(pad "AB3" smd circle
			(at -32.749998 -19.800062 180)
			(size 0.450088 0.450088)
			(layers "F.Cu" "F.Mask" "F.Paste")
			(net "GND")
		)
		(pad "AB4" smd circle
			(at -31.809944 -19.800062 180)
			(size 0.450088 0.450088)
			(layers "F.Cu" "F.Mask" "F.Paste")
			(net "M_G_CPU0_SA_DQ<21>")
		)
		(pad "AB5" smd circle
			(at -30.86989 -19.800062 180)
			(size 0.450088 0.450088)
			(layers "F.Cu" "F.Mask" "F.Paste")
			(net "GND")
		)
		(pad "AB6" smd circle
			(at -29.93009 -19.800062 180)
			(size 0.450088 0.450088)
			(layers "F.Cu" "F.Mask" "F.Paste")
			(net "M_K_CPU0_SA_DQ<22>")
		)
		(pad "AB7" smd circle
			(at -28.990036 -19.800062 180)
			(size 0.450088 0.450088)
			(layers "F.Cu" "F.Mask" "F.Paste")
			(net "M_K_CPU0_SA_DQ<21>")
		)
		(pad "AB8" smd circle
			(at -28.049982 -19.800062 180)
			(size 0.450088 0.450088)
			(layers "F.Cu" "F.Mask" "F.Paste")
			(net "GND")
		)
		(pad "AB9" smd circle
			(at -27.109928 -19.800062 180)
			(size 0.450088 0.450088)
			(layers "F.Cu" "F.Mask" "F.Paste")
			(net "M_L_CPU0_SA_DQ<22>")
		)
		(pad "AB10" smd circle
			(at -26.170128 -19.800062 180)
			(size 0.450088 0.450088)
			(layers "F.Cu" "F.Mask" "F.Paste")
			(net "GND")
		)
		(pad "AB11" smd circle
			(at -25.230074 -19.800062 180)
			(size 0.450088 0.450088)
			(layers "F.Cu" "F.Mask" "F.Paste")
			(net "M_L_CPU0_SA_DQ<21>")
		)
		(pad "AB12" smd circle
			(at -24.29002 -19.800062 180)
			(size 0.450088 0.450088)
			(layers "F.Cu" "F.Mask" "F.Paste")
			(net "GND")
		)
		(pad "AB13" smd circle
			(at -23.349966 -19.800062 180)
			(size 0.450088 0.450088)
			(layers "F.Cu" "F.Mask" "F.Paste")
			(net "M_H_CPU0_SA_DQ<22>")
		)
		(pad "AB14" smd circle
			(at -22.409912 -19.800062 180)
			(size 0.450088 0.450088)
			(layers "F.Cu" "F.Mask" "F.Paste")
			(net "M_H_CPU0_SA_DQ<21>")
		)
		(pad "AB15" smd circle
			(at -21.470112 -19.800062 180)
			(size 0.450088 0.450088)
			(layers "F.Cu" "F.Mask" "F.Paste")
			(net "GND")
		)
		(pad "AB16" smd circle
			(at -20.530058 -19.800062 180)
			(size 0.450088 0.450088)
			(layers "F.Cu" "F.Mask" "F.Paste")
			(net "M_J_CPU0_SA_DQ<22>")
		)
		(pad "AB17" smd circle
			(at -19.590004 -19.800062 180)
			(size 0.450088 0.450088)
			(layers "F.Cu" "F.Mask" "F.Paste")
			(net "GND")
		)
		(pad "AB18" smd circle
			(at -18.64995 -19.800062 180)
			(size 0.450088 0.450088)
			(layers "F.Cu" "F.Mask" "F.Paste")
			(net "M_J_CPU0_SA_DQ<21>")
		)
		(pad "AB19" smd circle
			(at -17.709896 -19.800062 180)
			(size 0.450088 0.450088)
			(layers "F.Cu" "F.Mask" "F.Paste")
			(net "GND")
		)
		(pad "AB20" smd circle
			(at -16.770096 -19.800062 180)
			(size 0.450088 0.450088)
			(layers "F.Cu" "F.Mask" "F.Paste")
			(net "M_I_CPU0_SA_DQ<22>")
		)
		(pad "AB21" smd circle
			(at -15.830042 -19.800062 180)
			(size 0.450088 0.450088)
			(layers "F.Cu" "F.Mask" "F.Paste")
			(net "M_I_CPU0_SA_DQ<21>")
		)
		(pad "AB22" smd circle
			(at -14.889988 -19.800062 180)
			(size 0.450088 0.450088)
			(layers "F.Cu" "F.Mask" "F.Paste")
			(net "GND")
		)
		(pad "AB23" smd circle
			(at -13.949934 -19.800062 180)
			(size 0.450088 0.450088)
			(layers "F.Cu" "F.Mask" "F.Paste")
			(net "PVDDCR_CPU0_P0")
		)
		(pad "AB24" smd circle
			(at -13.00988 -19.800062 180)
			(size 0.450088 0.450088)
			(layers "F.Cu" "F.Mask" "F.Paste")
			(net "PVDDCR_CPU0_P0")
		)
		(pad "AB25" smd circle
			(at -12.07008 -19.800062 180)
			(size 0.450088 0.450088)
			(layers "F.Cu" "F.Mask" "F.Paste")
			(net "GND")
		)
		(pad "AB26" smd circle
			(at -11.130026 -19.800062 180)
			(size 0.450088 0.450088)
			(layers "F.Cu" "F.Mask" "F.Paste")
			(net "PVDDCR_CPU0_P0")
		)
		(pad "AB27" smd circle
			(at -10.189972 -19.800062 180)
			(size 0.450088 0.450088)
			(layers "F.Cu" "F.Mask" "F.Paste")
			(net "PVDDCR_CPU0_P0")
		)
		(pad "AB28" smd circle
			(at -9.249918 -19.800062 180)
			(size 0.450088 0.450088)
			(layers "F.Cu" "F.Mask" "F.Paste")
			(net "GND")
		)
		(pad "AB29" smd circle
			(at -8.310118 -19.800062 180)
			(size 0.450088 0.450088)
			(layers "F.Cu" "F.Mask" "F.Paste")
			(net "PVDDCR_CPU0_P0")
		)
		(pad "AB30" smd circle
			(at -7.370064 -19.800062 180)
			(size 0.450088 0.450088)
			(layers "F.Cu" "F.Mask" "F.Paste")
			(net "PVDDCR_CPU0_P0")
		)
		(pad "AB31" smd circle
			(at -6.43001 -19.800062 180)
			(size 0.450088 0.450088)
			(layers "F.Cu" "F.Mask" "F.Paste")
			(net "GND")
		)
		(pad "AB32" smd circle
			(at -5.489956 -19.800062 180)
			(size 0.450088 0.450088)
			(layers "F.Cu" "F.Mask" "F.Paste")
			(net "PVDDCR_CPU0_P0")
		)
		(pad "AB33" smd circle
			(at -4.549902 -19.800062 180)
			(size 0.450088 0.450088)
			(layers "F.Cu" "F.Mask" "F.Paste")
			(net "PVDDCR_CPU0_P0")
		)
		(pad "AB34" smd circle
			(at -3.610102 -19.800062 180)
			(size 0.450088 0.450088)
			(layers "F.Cu" "F.Mask" "F.Paste")
			(net "GND")
		)
		(pad "AB35" smd circle
			(at -2.670048 -19.800062 180)
			(size 0.450088 0.450088)
			(layers "F.Cu" "F.Mask" "F.Paste")
			(net "GMI_CPU1_G0_CPU0_G2_TX_DN<13>")
		)
		(pad "AB36" smd circle
			(at -1.729994 -19.800062 180)
			(size 0.450088 0.450088)
			(layers "F.Cu" "F.Mask" "F.Paste")
			(net "GMI_CPU1_G0_CPU0_G2_TX_DP<13>")
		)
		(pad "AB37" smd circle
			(at -0.78994 -19.800062 180)
			(size 0.450088 0.450088)
			(layers "F.Cu" "F.Mask" "F.Paste")
			(net "GND")
		)
		(pad "AB39" smd circle
			(at 1.089914 -19.800062 180)
			(size 0.450088 0.450088)
			(layers "F.Cu" "F.Mask" "F.Paste")
			(net "GND")
		)
		(pad "AB40" smd circle
			(at 2.029968 -19.800062 180)
			(size 0.450088 0.450088)
			(layers "F.Cu" "F.Mask" "F.Paste")
			(net "GMI_CPU0_G0_CPU1_G2_TX_DP<2>")
		)
		(pad "AB41" smd circle
			(at 2.970022 -19.800062 180)
			(size 0.450088 0.450088)
			(layers "F.Cu" "F.Mask" "F.Paste")
			(net "GMI_CPU0_G0_CPU1_G2_TX_DN<2>")
		)
		(pad "AB42" smd circle
			(at 3.910076 -19.800062 180)
			(size 0.450088 0.450088)
			(layers "F.Cu" "F.Mask" "F.Paste")
			(net "GND")
		)
		(pad "AB43" smd circle
			(at 4.849876 -19.800062 180)
			(size 0.450088 0.450088)
			(layers "F.Cu" "F.Mask" "F.Paste")
			(net "PVDDCR_CPU0_P0")
		)
		(pad "AB44" smd circle
			(at 5.78993 -19.800062 180)
			(size 0.450088 0.450088)
			(layers "F.Cu" "F.Mask" "F.Paste")
			(net "PVDDCR_CPU0_P0")
		)
		(pad "AB45" smd circle
			(at 6.729984 -19.800062 180)
			(size 0.450088 0.450088)
			(layers "F.Cu" "F.Mask" "F.Paste")
			(net "GND")
		)
		(pad "AB46" smd circle
			(at 7.670038 -19.800062 180)
			(size 0.450088 0.450088)
			(layers "F.Cu" "F.Mask" "F.Paste")
			(net "PVDDCR_CPU0_P0")
		)
		(pad "AB47" smd circle
			(at 8.610092 -19.800062 180)
			(size 0.450088 0.450088)
			(layers "F.Cu" "F.Mask" "F.Paste")
			(net "PVDDCR_CPU0_P0")
		)
		(pad "AB48" smd circle
			(at 9.549892 -19.800062 180)
			(size 0.450088 0.450088)
			(layers "F.Cu" "F.Mask" "F.Paste")
			(net "GND")
		)
		(pad "AB49" smd circle
			(at 10.489946 -19.800062 180)
			(size 0.450088 0.450088)
			(layers "F.Cu" "F.Mask" "F.Paste")
			(net "PVDDCR_CPU0_P0")
		)
		(pad "AB50" smd circle
			(at 11.43 -19.800062 180)
			(size 0.450088 0.450088)
			(layers "F.Cu" "F.Mask" "F.Paste")
			(net "PVDDCR_CPU0_P0")
		)
		(pad "AB51" smd circle
			(at 12.370054 -19.800062 180)
			(size 0.450088 0.450088)
			(layers "F.Cu" "F.Mask" "F.Paste")
			(net "GND")
		)
		(pad "AB52" smd circle
			(at 13.310108 -19.800062 180)
			(size 0.450088 0.450088)
			(layers "F.Cu" "F.Mask" "F.Paste")
			(net "PVDDCR_CPU0_P0")
		)
		(pad "AB53" smd circle
			(at 14.249908 -19.800062 180)
			(size 0.450088 0.450088)
			(layers "F.Cu" "F.Mask" "F.Paste")
			(net "PVDDCR_CPU0_P0")
		)
		(pad "AB54" smd circle
			(at 15.189962 -19.800062 180)
			(size 0.450088 0.450088)
			(layers "F.Cu" "F.Mask" "F.Paste")
			(net "GND")
		)
		(pad "AB55" smd circle
			(at 16.130016 -19.800062 180)
			(size 0.450088 0.450088)
			(layers "F.Cu" "F.Mask" "F.Paste")
			(net "M_C_CPU0_SA_DQ<21>")
		)
		(pad "AB56" smd circle
			(at 17.07007 -19.800062 180)
			(size 0.450088 0.450088)
			(layers "F.Cu" "F.Mask" "F.Paste")
			(net "M_C_CPU0_SA_DQ<22>")
		)
		(pad "AB57" smd circle
			(at 18.010124 -19.800062 180)
			(size 0.450088 0.450088)
			(layers "F.Cu" "F.Mask" "F.Paste")
			(net "GND")
		)
		(pad "AB58" smd circle
			(at 18.949924 -19.800062 180)
			(size 0.450088 0.450088)
			(layers "F.Cu" "F.Mask" "F.Paste")
			(net "M_D_CPU0_SA_DQ<21>")
		)
		(pad "AB59" smd circle
			(at 19.889978 -19.800062 180)
			(size 0.450088 0.450088)
			(layers "F.Cu" "F.Mask" "F.Paste")
			(net "GND")
		)
		(pad "AB60" smd circle
			(at 20.830032 -19.800062 180)
			(size 0.450088 0.450088)
			(layers "F.Cu" "F.Mask" "F.Paste")
			(net "M_D_CPU0_SA_DQ<22>")
		)
		(pad "AB61" smd circle
			(at 21.770086 -19.800062 180)
			(size 0.450088 0.450088)
			(layers "F.Cu" "F.Mask" "F.Paste")
			(net "GND")
		)
		(pad "AB62" smd circle
			(at 22.709886 -19.800062 180)
			(size 0.450088 0.450088)
			(layers "F.Cu" "F.Mask" "F.Paste")
			(net "M_B_CPU0_SA_DQ<21>")
		)
		(pad "AB63" smd circle
			(at 23.64994 -19.800062 180)
			(size 0.450088 0.450088)
			(layers "F.Cu" "F.Mask" "F.Paste")
			(net "M_B_CPU0_SA_DQ<22>")
		)
		(pad "AB64" smd circle
			(at 24.589994 -19.800062 180)
			(size 0.450088 0.450088)
			(layers "F.Cu" "F.Mask" "F.Paste")
			(net "GND")
		)
		(pad "AB65" smd circle
			(at 25.530048 -19.800062 180)
			(size 0.450088 0.450088)
			(layers "F.Cu" "F.Mask" "F.Paste")
			(net "M_F_CPU0_SA_DQ<21>")
		)
		(pad "AB66" smd circle
			(at 26.470102 -19.800062 180)
			(size 0.450088 0.450088)
			(layers "F.Cu" "F.Mask" "F.Paste")
			(net "GND")
		)
		(pad "AB67" smd circle
			(at 27.409902 -19.800062 180)
			(size 0.450088 0.450088)
			(layers "F.Cu" "F.Mask" "F.Paste")
			(net "M_F_CPU0_SA_DQ<22>")
		)
		(pad "AB68" smd circle
			(at 28.349956 -19.800062 180)
			(size 0.450088 0.450088)
			(layers "F.Cu" "F.Mask" "F.Paste")
			(net "GND")
		)
		(pad "AB69" smd circle
			(at 29.29001 -19.800062 180)
			(size 0.450088 0.450088)
			(layers "F.Cu" "F.Mask" "F.Paste")
			(net "M_E_CPU0_SA_DQ<21>")
		)
		(pad "AB70" smd circle
			(at 30.230064 -19.800062 180)
			(size 0.450088 0.450088)
			(layers "F.Cu" "F.Mask" "F.Paste")
			(net "M_E_CPU0_SA_DQ<22>")
		)
		(pad "AB71" smd circle
			(at 31.170118 -19.800062 180)
			(size 0.450088 0.450088)
			(layers "F.Cu" "F.Mask" "F.Paste")
			(net "GND")
		)
		(pad "AB72" smd circle
			(at 32.109918 -19.800062 180)
			(size 0.450088 0.450088)
			(layers "F.Cu" "F.Mask" "F.Paste")
			(net "M_A_CPU0_SA_DQ<21>")
		)
		(pad "AB73" smd circle
			(at 33.049972 -19.800062 180)
			(size 0.450088 0.450088)
			(layers "F.Cu" "F.Mask" "F.Paste")
			(net "GND")
		)
		(pad "AB74" smd circle
			(at 33.990026 -19.800062 180)
			(size 0.450088 0.450088)
			(layers "F.Cu" "F.Mask" "F.Paste")
			(net "M_A_CPU0_SA_DQ<22>")
		)
		(pad "AC1" smd circle
			(at -34.159952 -18.990056 180)
			(size 0.450088 0.450088)
			(layers "F.Cu" "F.Mask" "F.Paste")
			(net "GND")
		)
		(pad "AC2" smd circle
			(at -33.219898 -18.990056 180)
			(size 0.450088 0.450088)
			(layers "F.Cu" "F.Mask" "F.Paste")
			(net "M_G_CPU0_SA_DQ<24>")
		)
		(pad "AC3" smd circle
			(at -32.280098 -18.990056 180)
			(size 0.450088 0.450088)
			(layers "F.Cu" "F.Mask" "F.Paste")
			(net "M_G_CPU0_SA_DQ<23>")
		)
		(pad "AC4" smd circle
			(at -31.340044 -18.990056 180)
			(size 0.450088 0.450088)
			(layers "F.Cu" "F.Mask" "F.Paste")
			(net "PVDDCR_SOC_P0")
		)
		(pad "AC5" smd circle
			(at -30.39999 -18.990056 180)
			(size 0.450088 0.450088)
			(layers "F.Cu" "F.Mask" "F.Paste")
			(net "M_K_CPU0_SA_DQ<24>")
		)
		(pad "AC6" smd circle
			(at -29.459936 -18.990056 180)
			(size 0.450088 0.450088)
			(layers "F.Cu" "F.Mask" "F.Paste")
			(net "GND")
		)
		(pad "AC7" smd circle
			(at -28.519882 -18.990056 180)
			(size 0.450088 0.450088)
			(layers "F.Cu" "F.Mask" "F.Paste")
			(net "M_K_CPU0_SA_DQ<23>")
		)
		(pad "AC8" smd circle
			(at -27.580082 -18.990056 180)
			(size 0.450088 0.450088)
			(layers "F.Cu" "F.Mask" "F.Paste")
			(net "GND")
		)
		(pad "AC9" smd circle
			(at -26.640028 -18.990056 180)
			(size 0.450088 0.450088)
			(layers "F.Cu" "F.Mask" "F.Paste")
			(net "M_L_CPU0_SA_DQ<24>")
		)
		(pad "AC10" smd circle
			(at -25.699974 -18.990056 180)
			(size 0.450088 0.450088)
			(layers "F.Cu" "F.Mask" "F.Paste")
			(net "M_L_CPU0_SA_DQ<23>")
		)
		(pad "AC11" smd circle
			(at -24.75992 -18.990056 180)
			(size 0.450088 0.450088)
			(layers "F.Cu" "F.Mask" "F.Paste")
			(net "PVDDCR_SOC_P0")
		)
		(pad "AC12" smd circle
			(at -23.82012 -18.990056 180)
			(size 0.450088 0.450088)
			(layers "F.Cu" "F.Mask" "F.Paste")
			(net "M_H_CPU0_SA_DQ<24>")
		)
	)
)
